(kicad_pcb
	(version 20241229)
	(generator "pcbnew")
	(generator_version "9.0")
	(general
		(thickness 1.6296)
		(legacy_teardrops no)
	)
	(paper "A3")
	(title_block
		(title "Thunderbolt to 10GbE adapter")
		(date "2026-04-21")
		(rev "1.1.0")
		(company "Antmicro Ltd")
		(comment 1 "www.antmicro.com")
		(comment 9 "footprints 119-122 of 703")
	)
	(layers
		(0 "F.Cu" signal)
		(4 "In1.Cu" signal)
		(6 "In2.Cu" signal)
		(8 "In3.Cu" signal)
		(10 "In4.Cu" signal)
		(12 "In5.Cu" signal)
		(14 "In6.Cu" signal)
		(2 "B.Cu" signal)
		(9 "F.Adhes" user "F.Adhesive")
		(11 "B.Adhes" user "B.Adhesive")
		(13 "F.Paste" user)
		(15 "B.Paste" user)
		(5 "F.SilkS" user "F.Silkscreen")
		(7 "B.SilkS" user "B.Silkscreen")
		(1 "F.Mask" user)
		(3 "B.Mask" user)
		(17 "Dwgs.User" user "User.Drawings")
		(19 "Cmts.User" user "User.Comments")
		(21 "Eco1.User" user "User.Eco1")
		(23 "Eco2.User" user "User.Eco2")
		(25 "Edge.Cuts" user)
		(27 "Margin" user)
		(31 "F.CrtYd" user "F.Courtyard")
		(29 "B.CrtYd" user "B.Courtyard")
		(35 "F.Fab" user)
		(33 "B.Fab" user)
	)
	(footprint "antmicro-footprints:C_0402_1005Metric"
		(layer "F.Cu")
		(at 159.249996 111.15 180)
		(descr "Capacitor SMD 0402")
		(tags "capacitor SMD 0402")
		(property "Reference" "C132"
			(at -12.950004 -17.25 180)
			(layer "F.SilkS")
			(effects
				(font
					(size 0.7 0.7)
					(thickness 0.15)
				)
			)
		)
		(property "Value" "C_33p_0402"
			(at -1.022927 2.155213 180)
			(layer "F.Fab")
			(effects
				(font
					(size 0.7 0.7)
					(thickness 0.15)
				)
				(justify left bottom)
			)
		)
		(property "Datasheet" "https://spicat.kyocera-avx.com/product/mlcc/chartview/04025A330FAT2A/"
			(at 0 0 180)
			(layer "F.Fab")
			(hide yes)
			(effects
				(font
					(size 1.27 1.27)
					(thickness 0.15)
				)
			)
		)
		(property "Description" "SMD Multilayer Ceramic Capacitor, 33 pF, 50 V, 0402 [1005 Metric], ± 5%, C0G / NP0, MC"
			(at 0 0 180)
			(layer "F.Fab")
			(hide yes)
			(effects
				(font
					(size 1.27 1.27)
					(thickness 0.15)
				)
			)
		)
		(property "MPN" "04025A330FAT2A"
			(at 0 0 180)
			(unlocked yes)
			(layer "F.Fab")
			(hide yes)
			(effects
				(font
					(size 1 1)
					(thickness 0.15)
				)
			)
		)
		(property "Manufacturer" "KYOCERA AVX"
			(at 0 0 180)
			(unlocked yes)
			(layer "F.Fab")
			(hide yes)
			(effects
				(font
					(size 1 1)
					(thickness 0.15)
				)
			)
		)
		(property "License" "Apache-2.0"
			(at 0 0 180)
			(unlocked yes)
			(layer "F.Fab")
			(hide yes)
			(effects
				(font
					(size 1 1)
					(thickness 0.15)
				)
			)
		)
		(property "Author" "Antmicro"
			(at 0 0 180)
			(unlocked yes)
			(layer "F.Fab")
			(hide yes)
			(effects
				(font
					(size 1 1)
					(thickness 0.15)
				)
			)
		)
		(property "Val" "33p"
			(at 0 0 180)
			(unlocked yes)
			(layer "F.Fab")
			(hide yes)
			(effects
				(font
					(size 1 1)
					(thickness 0.15)
				)
			)
		)
		(property "Voltage" ""
			(at 0 0 180)
			(unlocked yes)
			(layer "F.Fab")
			(hide yes)
			(effects
				(font
					(size 1 1)
					(thickness 0.15)
				)
			)
		)
		(property "Dielectric" ""
			(at 0 0 180)
			(unlocked yes)
			(layer "F.Fab")
			(hide yes)
			(effects
				(font
					(size 1 1)
					(thickness 0.15)
				)
			)
		)
		(sheetname "/X710 DCDC converters/")
		(sheetfile "DCDC_converters_X710.kicad_sch")
		(attr smd dnp)
		(fp_rect
			(start -0.925 -0.47)
			(end 0.925 0.47)
			(stroke
				(width 0.05)
				(type default)
			)
			(fill no)
			(layer "F.CrtYd")
		)
		(fp_line
			(start 0.504 0.248)
			(end -0.494 0.248)
			(stroke
				(width 0.15)
				(type solid)
			)
			(layer "F.Fab")
		)
		(fp_line
			(start 0.504 -0.25)
			(end 0.504 0.248)
			(stroke
				(width 0.15)
				(type solid)
			)
			(layer "F.Fab")
		)
		(fp_line
			(start -0.494 0.248)
			(end -0.494 -0.25)
			(stroke
				(width 0.15)
				(type solid)
			)
			(layer "F.Fab")
		)
		(fp_line
			(start -0.494 -0.25)
			(end 0.504 -0.25)
			(stroke
				(width 0.15)
				(type solid)
			)
			(layer "F.Fab")
		)
		(fp_text user "License: Apache-2.0"
			(at -0.939 5.799 180)
			(layer "F.Fab")
			(effects
				(font
					(size 0.7 0.7)
					(thickness 0.15)
				)
				(justify left bottom)
			)
		)
		(fp_text user "${REFERENCE}"
			(at -0.939 4.599 180)
			(layer "F.Fab")
			(effects
				(font
					(size 0.7 0.7)
					(thickness 0.15)
				)
				(justify left bottom)
			)
		)
		(fp_text user "Author: Antmicro"
			(at -0.939 3.399 180)
			(layer "F.Fab")
			(effects
				(font
					(size 0.7 0.7)
					(thickness 0.15)
				)
				(justify left bottom)
			)
		)
		(pad "1" smd roundrect
			(at -0.48 0 180)
			(size 0.59 0.64)
			(layers "F.Cu" "F.Mask" "F.Paste")
			(roundrect_rratio 0.25)
			(net 340 "/X710 DCDC converters/1V0_FB")
			(pintype "passive")
		)
		(pad "2" smd roundrect
			(at 0.48 0 180)
			(size 0.59 0.64)
			(layers "F.Cu" "F.Mask" "F.Paste")
			(roundrect_rratio 0.25)
			(net 339 "/X710 DCDC converters/+1V0_OUT")
			(pintype "passive")
		)
	)
	(footprint "antmicro-footprints:C_0603_1608Metric"
		(layer "F.Cu")
		(at 150.305 66.024999 90)
		(descr "Capacitor SMD 0603")
		(tags "capacitor 0603")
		(property "Reference" "C209"
			(at 12.424999 20.045 90)
			(layer "F.SilkS")
			(effects
				(font
					(size 0.65 0.65)
					(thickness 0.1625)
					(bold yes)
				)
			)
		)
		(property "Value" "C_10u_10V_X7R_0603"
			(at -1.42757 1.770288 90)
			(layer "F.Fab")
			(effects
				(font
					(size 0.7 0.7)
					(thickness 0.15)
				)
				(justify left bottom)
			)
		)
		(property "Datasheet" "https://www.murata.com/products/productdetail?partno=GRM188Z71A106KA73%23"
			(at 0 0 90)
			(layer "F.Fab")
			(hide yes)
			(effects
				(font
					(size 1.27 1.27)
					(thickness 0.15)
				)
			)
		)
		(property "Description" "SMD Multilayer Ceramic Capacitor,  10µF, 10V, 0603, ±10%, X7R"
			(at 0 0 90)
			(layer "F.Fab")
			(hide yes)
			(effects
				(font
					(size 1.27 1.27)
					(thickness 0.15)
				)
			)
		)
		(property "MPN" "GRM188Z71A106KA73D"
			(at 0 0 90)
			(unlocked yes)
			(layer "F.Fab")
			(hide yes)
			(effects
				(font
					(size 1 1)
					(thickness 0.15)
				)
			)
		)
		(property "Val" "10u"
			(at 0 0 90)
			(unlocked yes)
			(layer "F.Fab")
			(hide yes)
			(effects
				(font
					(size 1 1)
					(thickness 0.15)
				)
			)
		)
		(property "Voltage" "10V"
			(at 0 0 90)
			(unlocked yes)
			(layer "F.Fab")
			(hide yes)
			(effects
				(font
					(size 1 1)
					(thickness 0.15)
				)
			)
		)
		(property "Dielectric" "X7R"
			(at 0 0 90)
			(unlocked yes)
			(layer "F.Fab")
			(hide yes)
			(effects
				(font
					(size 1 1)
					(thickness 0.15)
				)
			)
		)
		(property "Manufacturer" "Murata"
			(at 0 0 90)
			(unlocked yes)
			(layer "F.Fab")
			(hide yes)
			(effects
				(font
					(size 1 1)
					(thickness 0.15)
				)
			)
		)
		(property "License" "Apache-2.0"
			(at 0 0 90)
			(unlocked yes)
			(layer "F.Fab")
			(hide yes)
			(effects
				(font
					(size 1 1)
					(thickness 0.15)
				)
			)
		)
		(property "Author" "Antmicro"
			(at 0 0 90)
			(unlocked yes)
			(layer "F.Fab")
			(hide yes)
			(effects
				(font
					(size 1 1)
					(thickness 0.15)
				)
			)
		)
		(sheetname "/X710-AT2 power/")
		(sheetfile "x710-at2-power.kicad_sch")
		(attr smd)
		(fp_line
			(start -0.15 -0.4)
			(end 0.15 -0.4)
			(stroke
				(width 0.15)
				(type solid)
			)
			(layer "F.SilkS")
		)
		(fp_line
			(start -0.15 0.4)
			(end 0.15 0.4)
			(stroke
				(width 0.15)
				(type solid)
			)
			(layer "F.SilkS")
		)
		(fp_rect
			(start -1.25 -0.65)
			(end 1.25 0.65)
			(stroke
				(width 0.05)
				(type solid)
			)
			(fill no)
			(layer "F.CrtYd")
		)
		(fp_rect
			(start -0.8 -0.4)
			(end 0.8 0.4)
			(stroke
				(width 0.15)
				(type solid)
			)
			(fill no)
			(layer "F.Fab")
		)
		(fp_text user "License: Apache-2.0"
			(at -1.682 5.895 90)
			(layer "F.Fab")
			(effects
				(font
					(size 0.7 0.7)
					(thickness 0.15)
				)
				(justify left bottom)
			)
		)
		(fp_text user "${REFERENCE}"
			(at -1.682 3.895 90)
			(layer "F.Fab")
			(effects
				(font
					(size 0.7 0.7)
					(thickness 0.15)
				)
				(justify left bottom)
			)
		)
		(fp_text user "Author: Antmicro"
			(at -1.682 4.894 90)
			(layer "F.Fab")
			(effects
				(font
					(size 0.7 0.7)
					(thickness 0.15)
				)
				(justify left bottom)
			)
		)
		(pad "1" smd roundrect
			(at -0.7 0 90)
			(size 0.8 1)
			(layers "F.Cu" "F.Mask" "F.Paste")
			(roundrect_rratio 0.2)
			(net 23 "GND")
			(pintype "passive")
		)
		(pad "2" smd roundrect
			(at 0.7 0 90)
			(size 0.8 1)
			(layers "F.Cu" "F.Mask" "F.Paste")
			(roundrect_rratio 0.2)
			(net 1 "VCCA")
			(pintype "passive")
		)
	)
	(footprint "antmicro-footprints:R_0603_1608Metric"
		(layer "F.Cu")
		(at 158.2 103.05 90)
		(descr "Resistor SMD 0603")
		(tags "resistor SMD 0603")
		(property "Reference" "R111"
			(at -17.649996 13.250002 90)
			(layer "F.SilkS")
			(effects
				(font
					(size 0.7 0.7)
					(thickness 0.15)
				)
			)
		)
		(property "Value" "R_0R_22.4A_0603"
			(at 0 1.6 90)
			(layer "F.Fab")
			(effects
				(font
					(size 0.7 0.7)
					(thickness 0.15)
				)
				(justify left bottom)
			)
		)
		(property "Datasheet" "https://fscdn.rohm.com/en/products/databook/datasheet/passive/resistor/chip_resistor/pmr-jpw-e.pdf"
			(at 0 0 90)
			(layer "F.Fab")
			(hide yes)
			(effects
				(font
					(size 1.27 1.27)
					(thickness 0.15)
				)
			)
		)
		(property "Description" "SMD Chip Resistor"
			(at 0 0 90)
			(layer "F.Fab")
			(hide yes)
			(effects
				(font
					(size 1.27 1.27)
					(thickness 0.15)
				)
			)
		)
		(property "MPN" "PMR03EZPJ000"
			(at 0 0 90)
			(unlocked yes)
			(layer "F.Fab")
			(hide yes)
			(effects
				(font
					(size 1 1)
					(thickness 0.15)
				)
			)
		)
		(property "Manufacturer" "ROHM Semiconductor"
			(at 0 0 90)
			(unlocked yes)
			(layer "F.Fab")
			(hide yes)
			(effects
				(font
					(size 1 1)
					(thickness 0.15)
				)
			)
		)
		(property "Val" "0R"
			(at 0 0 90)
			(unlocked yes)
			(layer "F.Fab")
			(hide yes)
			(effects
				(font
					(size 1 1)
					(thickness 0.15)
				)
			)
		)
		(property "Max. Curr." "22.4A"
			(at 0 0 90)
			(unlocked yes)
			(layer "F.Fab")
			(hide yes)
			(effects
				(font
					(size 1 1)
					(thickness 0.15)
				)
			)
		)
		(property "Author" "Antmicro"
			(at 0 0 90)
			(unlocked yes)
			(layer "F.Fab")
			(hide yes)
			(effects
				(font
					(size 1 1)
					(thickness 0.15)
				)
			)
		)
		(property "License" "Apache-2.0"
			(at 0 0 90)
			(unlocked yes)
			(layer "F.Fab")
			(hide yes)
			(effects
				(font
					(size 1 1)
					(thickness 0.15)
				)
			)
		)
		(property "Tolerance" "template_tolerance"
			(at 0 0 90)
			(unlocked yes)
			(layer "F.Fab")
			(hide yes)
			(effects
				(font
					(size 1 1)
					(thickness 0.15)
				)
			)
		)
		(sheetname "/X710 DCDC converters/")
		(sheetfile "DCDC_converters_X710.kicad_sch")
		(attr smd)
		(fp_line
			(start -0.15 -0.4)
			(end 0.15 -0.4)
			(stroke
				(width 0.15)
				(type solid)
			)
			(layer "F.SilkS")
		)
		(fp_line
			(start -0.15 0.4)
			(end 0.15 0.4)
			(stroke
				(width 0.15)
				(type solid)
			)
			(layer "F.SilkS")
		)
		(fp_rect
			(start -1.25 -0.65)
			(end 1.25 0.65)
			(stroke
				(width 0.05)
				(type solid)
			)
			(fill no)
			(layer "F.CrtYd")
		)
		(fp_rect
			(start -0.8 -0.4)
			(end 0.8 0.4)
			(stroke
				(width 0.15)
				(type solid)
			)
			(fill no)
			(layer "F.Fab")
		)
		(fp_text user "License: Apache-2.0"
			(at -1.25 5.9 90)
			(layer "F.Fab")
			(effects
				(font
					(size 0.7 0.7)
					(thickness 0.15)
				)
				(justify left bottom)
			)
		)
		(fp_text user "${REFERENCE}"
			(at -1.25 3.898 90)
			(layer "F.Fab")
			(effects
				(font
					(size 0.7 0.7)
					(thickness 0.15)
				)
				(justify left bottom)
			)
		)
		(fp_text user "Author: Antmicro"
			(at -1.25 4.9 90)
			(layer "F.Fab")
			(effects
				(font
					(size 0.7 0.7)
					(thickness 0.15)
				)
				(justify left bottom)
			)
		)
		(pad "1" smd roundrect
			(at -0.7 0 90)
			(size 0.8 1)
			(layers "F.Cu" "F.Mask" "F.Paste")
			(roundrect_rratio 0.2)
			(net 339 "/X710 DCDC converters/+1V0_OUT")
			(pintype "passive")
		)
		(pad "2" smd roundrect
			(at 0.7 0 90)
			(size 0.8 1)
			(layers "F.Cu" "F.Mask" "F.Paste")
			(roundrect_rratio 0.2)
			(net 136 "+1V0")
			(pintype "passive")
		)
	)
	(footprint "antmicro-footprints:R_0402_1005Metric"
		(layer "F.Cu")
		(at 116.4 104.1)
		(descr "Resistor SMD 0402")
		(tags "resistor SMD 0402")
		(property "Reference" "R20"
			(at 0 -8.1 0)
			(layer "F.SilkS")
			(effects
				(font
					(size 0.7 0.7)
					(thickness 0.15)
				)
			)
		)
		(property "Value" "R_100k_0402"
			(at -1.011843 1.772047 0)
			(layer "F.Fab")
			(effects
				(font
					(size 0.7 0.7)
					(thickness 0.15)
				)
				(justify left bottom)
			)
		)
		(property "Datasheet" "https://www.bourns.com/docs/product-datasheets/cr.pdf"
			(at 0 0 0)
			(layer "F.Fab")
			(hide yes)
			(effects
				(font
					(size 1.27 1.27)
					(thickness 0.15)
				)
			)
		)
		(property "Description" "SMD Chip Resistor, 100 kohm, ± 1%, 62.5 mW, 0402 [1005 Metric], Thick Film, General Purpose"
			(at 0 0 0)
			(layer "F.Fab")
			(hide yes)
			(effects
				(font
					(size 1.27 1.27)
					(thickness 0.15)
				)
			)
		)
		(property "MPN" "CR0402-FX-1003GLF"
			(at 0 0 0)
			(unlocked yes)
			(layer "F.Fab")
			(hide yes)
			(effects
				(font
					(size 1 1)
					(thickness 0.15)
				)
			)
		)
		(property "Manufacturer" "Bourns"
			(at 0 0 0)
			(unlocked yes)
			(layer "F.Fab")
			(hide yes)
			(effects
				(font
					(size 1 1)
					(thickness 0.15)
				)
			)
		)
		(property "License" "Apache-2.0"
			(at 0 0 0)
			(unlocked yes)
			(layer "F.Fab")
			(hide yes)
			(effects
				(font
					(size 1 1)
					(thickness 0.15)
				)
			)
		)
		(property "Val" "100k"
			(at 0 0 0)
			(unlocked yes)
			(layer "F.Fab")
			(hide yes)
			(effects
				(font
					(size 1 1)
					(thickness 0.15)
				)
			)
		)
		(property "Tolerance" "1%"
			(at 0 0 0)
			(unlocked yes)
			(layer "F.Fab")
			(hide yes)
			(effects
				(font
					(size 1 1)
					(thickness 0.15)
				)
			)
		)
		(property "Author" "Antmicro"
			(at 0 0 0)
			(unlocked yes)
			(layer "F.Fab")
			(hide yes)
			(effects
				(font
					(size 1 1)
					(thickness 0.15)
				)
			)
		)
		(sheetname "/PD and TB DC-DC/")
		(sheetfile "PD_and_TB_DC_DC.kicad_sch")
		(attr smd)
		(fp_rect
			(start -0.925 -0.47)
			(end 0.925 0.47)
			(stroke
				(width 0.05)
				(type default)
			)
			(fill no)
			(layer "F.CrtYd")
		)
		(fp_rect
			(start -0.5 -0.25)
			(end 0.5 0.25)
			(stroke
				(width 0.15)
				(type solid)
			)
			(fill no)
			(layer "F.Fab")
		)
		(fp_text user "License: Apache-2.0"
			(at -0.95 5.169 0)
			(layer "F.Fab")
			(effects
				(font
					(size 0.7 0.7)
					(thickness 0.15)
				)
				(justify left bottom)
			)
		)
		(fp_text user "${REFERENCE}"
			(at -0.95 3.168 0)
			(layer "F.Fab")
			(effects
				(font
					(size 0.7 0.7)
					(thickness 0.15)
				)
				(justify left bottom)
			)
		)
		(fp_text user "Author: Antmicro"
			(at -0.95 4.169 0)
			(layer "F.Fab")
			(effects
				(font
					(size 0.7 0.7)
					(thickness 0.15)
				)
				(justify left bottom)
			)
		)
		(pad "1" smd roundrect
			(at -0.48 0)
			(size 0.59 0.64)
			(layers "F.Cu" "F.Mask" "F.Paste")
			(roundrect_rratio 0.25)
			(net 17 "Net-(U2-PG)")
			(pintype "passive")
		)
		(pad "2" smd roundrect
			(at 0.48 0)
			(size 0.59 0.64)
			(layers "F.Cu" "F.Mask" "F.Paste")
			(roundrect_rratio 0.25)
			(net 303 "/PD and TB DC-DC/SMPS_LDO")
			(pintype "passive")
		)
	)
)
